(kicad_pcb
	(version 20260206)
	(generator "pcbnew")
	(generator_version "10.0")
	(general
		(thickness 1.6)
		(legacy_teardrops no)
	)
	(paper "A4")
	(title_block
		(title "03242023_DA0F0TMBIJ0_F0T_Motherboard_J_brd_V01_OCP.brd")
		(comment 1 "Grand Teton / footprints 5295-5302 of 6105")
	)
	(layers
		(0 "F.Cu" signal "TOP")
		(4 "In1.Cu" signal "GND")
		(6 "In2.Cu" signal "IN1")
		(8 "In3.Cu" signal "GND1")
		(10 "In4.Cu" signal "IN2")
		(12 "In5.Cu" signal "GND2")
		(14 "In6.Cu" signal "IN3")
		(16 "In7.Cu" signal "GND3")
		(18 "In8.Cu" signal "VCC")
		(20 "In9.Cu" signal "VCC1")
		(22 "In10.Cu" signal "GND4")
		(24 "In11.Cu" signal "IN4")
		(26 "In12.Cu" signal "GND5")
		(28 "In13.Cu" signal "IN5")
		(30 "In14.Cu" signal "GND6")
		(32 "In15.Cu" signal "IN6")
		(34 "In16.Cu" signal "GND7")
		(2 "B.Cu" signal "BOTTOM")
		(9 "F.Adhes" user "F.Adhesive")
		(11 "B.Adhes" user "B.Adhesive")
		(13 "F.Paste" user "Package Geometry/Pastemask Top")
		(15 "B.Paste" user "Package Geometry/Pastemask Bottom")
		(5 "F.SilkS" user "Ref Des/Silkscreen Top")
		(7 "B.SilkS" user "Ref Des/Silkscreen Bottom")
		(1 "F.Mask" user "Board Geometry/Soldermask Top")
		(3 "B.Mask" user "Board Geometry/Soldermask Bottom")
		(17 "Dwgs.User" user "User.Drawings")
		(19 "Cmts.User" user "User.Comments")
		(21 "Eco1.User" user "User.Eco1")
		(23 "Eco2.User" user "User.Eco2")
		(25 "Edge.Cuts" user "Board Geometry/Outline")
		(27 "Margin" user)
		(31 "F.CrtYd" user "Package Geometry/Place Bound Top")
		(29 "B.CrtYd" user "Package Geometry/Place Bound Bottom")
		(35 "F.Fab" user "Ref Des/Assembly Top")
		(33 "B.Fab" user "Ref Des/Assembly Bottom")
	)
	(footprint ""
		(layer "B.Cu")
		(at 151.281638 -190.35522 -90)
		(property "Reference" "R664"
			(at 0 0 90)
			(layer "B.SilkS")
			(hide yes)
			(effects
				(font
					(size 1.27 1.27)
				)
				(justify mirror)
			)
		)
		(property "Value" ""
			(at 0 0 90)
			(layer "B.Fab")
			(effects
				(font
					(size 1.27 1.27)
				)
				(justify mirror)
			)
		)
		(duplicate_pad_numbers_are_jumpers no)
		(fp_line
			(start -0.7874 0.4064)
			(end 0.7874 0.4064)
			(stroke
				(width 0.1524)
				(type default)
			)
			(layer "B.SilkS")
		)
		(fp_line
			(start 0.7874 0.4064)
			(end 0.7874 -0.4064)
			(stroke
				(width 0.1524)
				(type default)
			)
			(layer "B.SilkS")
		)
		(fp_line
			(start -0.7874 -0.4064)
			(end -0.7874 0.4064)
			(stroke
				(width 0.1524)
				(type default)
			)
			(layer "B.SilkS")
		)
		(fp_line
			(start 0.7874 -0.4064)
			(end -0.7874 -0.4064)
			(stroke
				(width 0.1524)
				(type default)
			)
			(layer "B.SilkS")
		)
		(fp_line
			(start -0.67945 0.3048)
			(end -0.120396 0.3048)
			(stroke
				(width 0.1)
				(type default)
			)
			(layer "B.Fab")
		)
		(fp_line
			(start -0.120396 0.3048)
			(end -0.120396 0.2794)
			(stroke
				(width 0.1)
				(type default)
			)
			(layer "B.Fab")
		)
		(fp_line
			(start 0.12065 0.3048)
			(end 0.67945 0.3048)
			(stroke
				(width 0.1)
				(type default)
			)
			(layer "B.Fab")
		)
		(fp_line
			(start 0.67945 0.3048)
			(end 0.67945 -0.305054)
			(stroke
				(width 0.1)
				(type default)
			)
			(layer "B.Fab")
		)
		(fp_line
			(start -0.120396 0.2794)
			(end 0.12065 0.2794)
			(stroke
				(width 0.1)
				(type default)
			)
			(layer "B.Fab")
		)
		(fp_line
			(start 0.12065 0.2794)
			(end 0.12065 0.3048)
			(stroke
				(width 0.1)
				(type default)
			)
			(layer "B.Fab")
		)
		(fp_line
			(start -0.12065 -0.2794)
			(end -0.12065 -0.3048)
			(stroke
				(width 0.1)
				(type default)
			)
			(layer "B.Fab")
		)
		(fp_line
			(start 0.12065 -0.2794)
			(end -0.12065 -0.2794)
			(stroke
				(width 0.1)
				(type default)
			)
			(layer "B.Fab")
		)
		(fp_line
			(start -0.67945 -0.3048)
			(end -0.67945 0.3048)
			(stroke
				(width 0.1)
				(type default)
			)
			(layer "B.Fab")
		)
		(fp_line
			(start -0.12065 -0.3048)
			(end -0.67945 -0.3048)
			(stroke
				(width 0.1)
				(type default)
			)
			(layer "B.Fab")
		)
		(fp_line
			(start 0.12065 -0.305054)
			(end 0.12065 -0.2794)
			(stroke
				(width 0.1)
				(type default)
			)
			(layer "B.Fab")
		)
		(fp_line
			(start 0.67945 -0.305054)
			(end 0.12065 -0.305054)
			(stroke
				(width 0.1)
				(type default)
			)
			(layer "B.Fab")
		)
		(pad "1" smd circle
			(at 0.40005 0 90)
			(size 0 0)
			(layers "B.Cu" "B.Mask" "B.Paste")
			(net "PVNN_TERM_CPU1")
		)
		(pad "2" smd circle
			(at -0.40005 0 90)
			(size 0 0)
			(layers "B.Cu" "B.Mask" "B.Paste")
			(net "I3C_SPD_DDREFGH_CPU1_SCL")
		)
	)
	(footprint ""
		(layer "B.Cu")
		(at 430.600104 -134.494778)
		(property "Reference" "R2594"
			(at 0 0 0)
			(layer "B.SilkS")
			(hide yes)
			(effects
				(font
					(size 1.27 1.27)
				)
				(justify mirror)
			)
		)
		(property "Value" ""
			(at 0 0 0)
			(layer "B.Fab")
			(effects
				(font
					(size 1.27 1.27)
				)
				(justify mirror)
			)
		)
		(duplicate_pad_numbers_are_jumpers no)
		(fp_line
			(start -0.7874 -0.4064)
			(end -0.7874 0.4064)
			(stroke
				(width 0.1524)
				(type default)
			)
			(layer "B.SilkS")
		)
		(fp_line
			(start -0.7874 0.4064)
			(end 0.7874 0.4064)
			(stroke
				(width 0.1524)
				(type default)
			)
			(layer "B.SilkS")
		)
		(fp_line
			(start 0.7874 -0.4064)
			(end -0.7874 -0.4064)
			(stroke
				(width 0.1524)
				(type default)
			)
			(layer "B.SilkS")
		)
		(fp_line
			(start 0.7874 0.4064)
			(end 0.7874 -0.4064)
			(stroke
				(width 0.1524)
				(type default)
			)
			(layer "B.SilkS")
		)
		(fp_line
			(start -0.67945 -0.3048)
			(end -0.67945 0.3048)
			(stroke
				(width 0.1)
				(type default)
			)
			(layer "B.Fab")
		)
		(fp_line
			(start -0.67945 0.3048)
			(end -0.120396 0.3048)
			(stroke
				(width 0.1)
				(type default)
			)
			(layer "B.Fab")
		)
		(fp_line
			(start -0.12065 -0.3048)
			(end -0.67945 -0.3048)
			(stroke
				(width 0.1)
				(type default)
			)
			(layer "B.Fab")
		)
		(fp_line
			(start -0.12065 -0.2794)
			(end -0.12065 -0.3048)
			(stroke
				(width 0.1)
				(type default)
			)
			(layer "B.Fab")
		)
		(fp_line
			(start -0.120396 0.2794)
			(end 0.12065 0.2794)
			(stroke
				(width 0.1)
				(type default)
			)
			(layer "B.Fab")
		)
		(fp_line
			(start -0.120396 0.3048)
			(end -0.120396 0.2794)
			(stroke
				(width 0.1)
				(type default)
			)
			(layer "B.Fab")
		)
		(fp_line
			(start 0.12065 -0.305054)
			(end 0.12065 -0.2794)
			(stroke
				(width 0.1)
				(type default)
			)
			(layer "B.Fab")
		)
		(fp_line
			(start 0.12065 -0.2794)
			(end -0.12065 -0.2794)
			(stroke
				(width 0.1)
				(type default)
			)
			(layer "B.Fab")
		)
		(fp_line
			(start 0.12065 0.2794)
			(end 0.12065 0.3048)
			(stroke
				(width 0.1)
				(type default)
			)
			(layer "B.Fab")
		)
		(fp_line
			(start 0.12065 0.3048)
			(end 0.67945 0.3048)
			(stroke
				(width 0.1)
				(type default)
			)
			(layer "B.Fab")
		)
		(fp_line
			(start 0.67945 -0.305054)
			(end 0.12065 -0.305054)
			(stroke
				(width 0.1)
				(type default)
			)
			(layer "B.Fab")
		)
		(fp_line
			(start 0.67945 0.3048)
			(end 0.67945 -0.305054)
			(stroke
				(width 0.1)
				(type default)
			)
			(layer "B.Fab")
		)
		(pad "1" smd circle
			(at 0.40005 0 180)
			(size 0 0)
			(layers "B.Cu" "B.Mask" "B.Paste")
			(net "FM_PVCCINFAON_CPU0_EN")
		)
		(pad "2" smd circle
			(at -0.40005 0 180)
			(size 0 0)
			(layers "B.Cu" "B.Mask" "B.Paste")
			(net "PVCCINFAON_CPU0_EN_R")
		)
	)
	(footprint ""
		(layer "B.Cu")
		(at 112.020604 -296.05478)
		(property "Reference" "C348"
			(at 0 0 0)
			(layer "B.SilkS")
			(hide yes)
			(effects
				(font
					(size 1.27 1.27)
				)
				(justify mirror)
			)
		)
		(property "Value" ""
			(at 0 0 0)
			(layer "B.Fab")
			(effects
				(font
					(size 1.27 1.27)
				)
				(justify mirror)
			)
		)
		(duplicate_pad_numbers_are_jumpers no)
		(fp_line
			(start -1.524 -0.762)
			(end -1.524 0.762)
			(stroke
				(width 0.1524)
				(type default)
			)
			(layer "B.SilkS")
		)
		(fp_line
			(start -1.524 0.762)
			(end 1.524 0.762)
			(stroke
				(width 0.1524)
				(type default)
			)
			(layer "B.SilkS")
		)
		(fp_line
			(start 1.524 -0.762)
			(end -1.524 -0.762)
			(stroke
				(width 0.1524)
				(type default)
			)
			(layer "B.SilkS")
		)
		(fp_line
			(start 1.524 0.762)
			(end 1.524 -0.762)
			(stroke
				(width 0.1524)
				(type default)
			)
			(layer "B.SilkS")
		)
		(fp_line
			(start -1.1049 -0.724916)
			(end 1.1049 -0.724916)
			(stroke
				(width 0.1)
				(type default)
			)
			(layer "B.Fab")
		)
		(fp_line
			(start -1.1049 0.724916)
			(end -1.1049 -0.724916)
			(stroke
				(width 0.1)
				(type default)
			)
			(layer "B.Fab")
		)
		(fp_line
			(start 1.1049 -0.724916)
			(end 1.1049 0.724916)
			(stroke
				(width 0.1)
				(type default)
			)
			(layer "B.Fab")
		)
		(fp_line
			(start 1.1049 0.724916)
			(end -1.1049 0.724916)
			(stroke
				(width 0.1)
				(type default)
			)
			(layer "B.Fab")
		)
		(pad "1" smd rect
			(at 0.889 0)
			(size 1.016 1.27)
			(layers "B.Cu" "B.Mask" "B.Paste")
			(net "PVCCIN_CPU1")
		)
		(pad "2" smd rect
			(at -0.889 0)
			(size 1.016 1.27)
			(layers "B.Cu" "B.Mask" "B.Paste")
			(net "GND")
		)
	)
	(footprint ""
		(layer "B.Cu")
		(at 288.175192 -320.004948)
		(property "Reference" "R28"
			(at 0 0 0)
			(layer "B.SilkS")
			(hide yes)
			(effects
				(font
					(size 1.27 1.27)
				)
				(justify mirror)
			)
		)
		(property "Value" ""
			(at 0 0 0)
			(layer "B.Fab")
			(effects
				(font
					(size 1.27 1.27)
				)
				(justify mirror)
			)
		)
		(duplicate_pad_numbers_are_jumpers no)
		(fp_line
			(start -0.7874 -0.4064)
			(end -0.7874 0.4064)
			(stroke
				(width 0.1524)
				(type default)
			)
			(layer "B.SilkS")
		)
		(fp_line
			(start -0.7874 0.4064)
			(end 0.7874 0.4064)
			(stroke
				(width 0.1524)
				(type default)
			)
			(layer "B.SilkS")
		)
		(fp_line
			(start 0.7874 -0.4064)
			(end -0.7874 -0.4064)
			(stroke
				(width 0.1524)
				(type default)
			)
			(layer "B.SilkS")
		)
		(fp_line
			(start 0.7874 0.4064)
			(end 0.7874 -0.4064)
			(stroke
				(width 0.1524)
				(type default)
			)
			(layer "B.SilkS")
		)
		(fp_line
			(start -0.67945 -0.3048)
			(end -0.67945 0.3048)
			(stroke
				(width 0.1)
				(type default)
			)
			(layer "B.Fab")
		)
		(fp_line
			(start -0.67945 0.3048)
			(end -0.120396 0.3048)
			(stroke
				(width 0.1)
				(type default)
			)
			(layer "B.Fab")
		)
		(fp_line
			(start -0.12065 -0.3048)
			(end -0.67945 -0.3048)
			(stroke
				(width 0.1)
				(type default)
			)
			(layer "B.Fab")
		)
		(fp_line
			(start -0.12065 -0.2794)
			(end -0.12065 -0.3048)
			(stroke
				(width 0.1)
				(type default)
			)
			(layer "B.Fab")
		)
		(fp_line
			(start -0.120396 0.2794)
			(end 0.12065 0.2794)
			(stroke
				(width 0.1)
				(type default)
			)
			(layer "B.Fab")
		)
		(fp_line
			(start -0.120396 0.3048)
			(end -0.120396 0.2794)
			(stroke
				(width 0.1)
				(type default)
			)
			(layer "B.Fab")
		)
		(fp_line
			(start 0.12065 -0.305054)
			(end 0.12065 -0.2794)
			(stroke
				(width 0.1)
				(type default)
			)
			(layer "B.Fab")
		)
		(fp_line
			(start 0.12065 -0.2794)
			(end -0.12065 -0.2794)
			(stroke
				(width 0.1)
				(type default)
			)
			(layer "B.Fab")
		)
		(fp_line
			(start 0.12065 0.2794)
			(end 0.12065 0.3048)
			(stroke
				(width 0.1)
				(type default)
			)
			(layer "B.Fab")
		)
		(fp_line
			(start 0.12065 0.3048)
			(end 0.67945 0.3048)
			(stroke
				(width 0.1)
				(type default)
			)
			(layer "B.Fab")
		)
		(fp_line
			(start 0.67945 -0.305054)
			(end 0.12065 -0.305054)
			(stroke
				(width 0.1)
				(type default)
			)
			(layer "B.Fab")
		)
		(fp_line
			(start 0.67945 0.3048)
			(end 0.67945 -0.305054)
			(stroke
				(width 0.1)
				(type default)
			)
			(layer "B.Fab")
		)
		(pad "1" smd circle
			(at 0.40005 0 180)
			(size 0 0)
			(layers "B.Cu" "B.Mask" "B.Paste")
			(net "PD_CHB_CPU0_DIMM1_SAA")
		)
		(pad "2" smd circle
			(at -0.40005 0 180)
			(size 0 0)
			(layers "B.Cu" "B.Mask" "B.Paste")
			(net "GND")
		)
	)
	(footprint ""
		(layer "B.Cu")
		(at 336.1563 -42.537888)
		(property "Reference" "C1204"
			(at 0 0 0)
			(layer "B.SilkS")
			(hide yes)
			(effects
				(font
					(size 1.27 1.27)
				)
				(justify mirror)
			)
		)
		(property "Value" ""
			(at 0 0 0)
			(layer "B.Fab")
			(effects
				(font
					(size 1.27 1.27)
				)
				(justify mirror)
			)
		)
		(duplicate_pad_numbers_are_jumpers no)
		(fp_line
			(start -0.7874 -0.4064)
			(end -0.7874 0.4064)
			(stroke
				(width 0.1524)
				(type default)
			)
			(layer "B.SilkS")
		)
		(fp_line
			(start -0.7874 0.4064)
			(end 0.7874 0.4064)
			(stroke
				(width 0.1524)
				(type default)
			)
			(layer "B.SilkS")
		)
		(fp_line
			(start 0.7874 -0.4064)
			(end -0.7874 -0.4064)
			(stroke
				(width 0.1524)
				(type default)
			)
			(layer "B.SilkS")
		)
		(fp_line
			(start 0.7874 0.4064)
			(end 0.7874 -0.4064)
			(stroke
				(width 0.1524)
				(type default)
			)
			(layer "B.SilkS")
		)
		(fp_line
			(start -0.67945 -0.3048)
			(end -0.67945 0.3048)
			(stroke
				(width 0.1)
				(type default)
			)
			(layer "B.Fab")
		)
		(fp_line
			(start -0.67945 0.3048)
			(end -0.120396 0.3048)
			(stroke
				(width 0.1)
				(type default)
			)
			(layer "B.Fab")
		)
		(fp_line
			(start -0.12065 -0.3048)
			(end -0.67945 -0.3048)
			(stroke
				(width 0.1)
				(type default)
			)
			(layer "B.Fab")
		)
		(fp_line
			(start -0.12065 -0.2794)
			(end -0.12065 -0.3048)
			(stroke
				(width 0.1)
				(type default)
			)
			(layer "B.Fab")
		)
		(fp_line
			(start -0.120396 0.2794)
			(end 0.12065 0.2794)
			(stroke
				(width 0.1)
				(type default)
			)
			(layer "B.Fab")
		)
		(fp_line
			(start -0.120396 0.3048)
			(end -0.120396 0.2794)
			(stroke
				(width 0.1)
				(type default)
			)
			(layer "B.Fab")
		)
		(fp_line
			(start 0.12065 -0.305054)
			(end 0.12065 -0.2794)
			(stroke
				(width 0.1)
				(type default)
			)
			(layer "B.Fab")
		)
		(fp_line
			(start 0.12065 -0.2794)
			(end -0.12065 -0.2794)
			(stroke
				(width 0.1)
				(type default)
			)
			(layer "B.Fab")
		)
		(fp_line
			(start 0.12065 0.2794)
			(end 0.12065 0.3048)
			(stroke
				(width 0.1)
				(type default)
			)
			(layer "B.Fab")
		)
		(fp_line
			(start 0.12065 0.3048)
			(end 0.67945 0.3048)
			(stroke
				(width 0.1)
				(type default)
			)
			(layer "B.Fab")
		)
		(fp_line
			(start 0.67945 -0.305054)
			(end 0.12065 -0.305054)
			(stroke
				(width 0.1)
				(type default)
			)
			(layer "B.Fab")
		)
		(fp_line
			(start 0.67945 0.3048)
			(end 0.67945 -0.305054)
			(stroke
				(width 0.1)
				(type default)
			)
			(layer "B.Fab")
		)
		(pad "1" smd circle
			(at 0.40005 0 180)
			(size 0 0)
			(layers "B.Cu" "B.Mask" "B.Paste")
			(net "P1V05_PCH_AUX")
		)
		(pad "2" smd circle
			(at -0.40005 0 180)
			(size 0 0)
			(layers "B.Cu" "B.Mask" "B.Paste")
			(net "GND")
		)
	)
	(footprint ""
		(layer "B.Cu")
		(at 174.98568 -24.653748)
		(property "Reference" "PC2240"
			(at 0 0 0)
			(layer "B.SilkS")
			(hide yes)
			(effects
				(font
					(size 1.27 1.27)
				)
				(justify mirror)
			)
		)
		(property "Value" ""
			(at 0 0 0)
			(layer "B.Fab")
			(effects
				(font
					(size 1.27 1.27)
				)
				(justify mirror)
			)
		)
		(duplicate_pad_numbers_are_jumpers no)
		(fp_line
			(start -1.524 -0.762)
			(end -1.524 0.762)
			(stroke
				(width 0.1524)
				(type default)
			)
			(layer "B.SilkS")
		)
		(fp_line
			(start -1.524 0.762)
			(end 1.524 0.762)
			(stroke
				(width 0.1524)
				(type default)
			)
			(layer "B.SilkS")
		)
		(fp_line
			(start 1.524 -0.762)
			(end -1.524 -0.762)
			(stroke
				(width 0.1524)
				(type default)
			)
			(layer "B.SilkS")
		)
		(fp_line
			(start 1.524 0.762)
			(end 1.524 -0.762)
			(stroke
				(width 0.1524)
				(type default)
			)
			(layer "B.SilkS")
		)
		(fp_line
			(start -1.1049 -0.724916)
			(end 1.1049 -0.724916)
			(stroke
				(width 0.1)
				(type default)
			)
			(layer "B.Fab")
		)
		(fp_line
			(start -1.1049 0.724916)
			(end -1.1049 -0.724916)
			(stroke
				(width 0.1)
				(type default)
			)
			(layer "B.Fab")
		)
		(fp_line
			(start 1.1049 -0.724916)
			(end 1.1049 0.724916)
			(stroke
				(width 0.1)
				(type default)
			)
			(layer "B.Fab")
		)
		(fp_line
			(start 1.1049 0.724916)
			(end -1.1049 0.724916)
			(stroke
				(width 0.1)
				(type default)
			)
			(layer "B.Fab")
		)
		(pad "1" smd rect
			(at 0.889 0)
			(size 1.016 1.27)
			(layers "B.Cu" "B.Mask" "B.Paste")
			(net "P12V_SCM_R")
		)
		(pad "2" smd rect
			(at -0.889 0)
			(size 1.016 1.27)
			(layers "B.Cu" "B.Mask" "B.Paste")
			(net "GND")
		)
	)
	(footprint ""
		(layer "B.Cu")
		(at 275.244814 -321.549776 -90)
		(property "Reference" "C15"
			(at 0 0 90)
			(layer "B.SilkS")
			(hide yes)
			(effects
				(font
					(size 1.27 1.27)
				)
				(justify mirror)
			)
		)
		(property "Value" ""
			(at 0 0 90)
			(layer "B.Fab")
			(effects
				(font
					(size 1.27 1.27)
				)
				(justify mirror)
			)
		)
		(duplicate_pad_numbers_are_jumpers no)
		(fp_line
			(start -1.524 0.762)
			(end 1.524 0.762)
			(stroke
				(width 0.1524)
				(type default)
			)
			(layer "B.SilkS")
		)
		(fp_line
			(start 1.524 0.762)
			(end 1.524 -0.762)
			(stroke
				(width 0.1524)
				(type default)
			)
			(layer "B.SilkS")
		)
		(fp_line
			(start -1.524 -0.762)
			(end -1.524 0.762)
			(stroke
				(width 0.1524)
				(type default)
			)
			(layer "B.SilkS")
		)
		(fp_line
			(start 1.524 -0.762)
			(end -1.524 -0.762)
			(stroke
				(width 0.1524)
				(type default)
			)
			(layer "B.SilkS")
		)
		(fp_line
			(start -1.1049 0.724916)
			(end -1.1049 -0.724916)
			(stroke
				(width 0.1)
				(type default)
			)
			(layer "B.Fab")
		)
		(fp_line
			(start 1.1049 0.724916)
			(end -1.1049 0.724916)
			(stroke
				(width 0.1)
				(type default)
			)
			(layer "B.Fab")
		)
		(fp_line
			(start -1.1049 -0.724916)
			(end 1.1049 -0.724916)
			(stroke
				(width 0.1)
				(type default)
			)
			(layer "B.Fab")
		)
		(fp_line
			(start 1.1049 -0.724916)
			(end 1.1049 0.724916)
			(stroke
				(width 0.1)
				(type default)
			)
			(layer "B.Fab")
		)
		(pad "1" smd rect
			(at 0.889 0 270)
			(size 1.016 1.27)
			(layers "B.Cu" "B.Mask" "B.Paste")
			(net "P12V_S3_AUX_CPU0_NVDIMM")
		)
		(pad "2" smd rect
			(at -0.889 0 270)
			(size 1.016 1.27)
			(layers "B.Cu" "B.Mask" "B.Paste")
			(net "GND")
		)
	)
	(footprint ""
		(layer "B.Cu")
		(at 352.402902 -210.19389)
		(property "Reference" "C500"
			(at 0 0 0)
			(layer "B.SilkS")
			(hide yes)
			(effects
				(font
					(size 1.27 1.27)
				)
				(justify mirror)
			)
		)
		(property "Value" ""
			(at 0 0 0)
			(layer "B.Fab")
			(effects
				(font
					(size 1.27 1.27)
				)
				(justify mirror)
			)
		)
		(duplicate_pad_numbers_are_jumpers no)
		(fp_line
			(start -1.524 -0.762)
			(end -1.524 0.762)
			(stroke
				(width 0.1524)
				(type default)
			)
			(layer "B.SilkS")
		)
		(fp_line
			(start -1.524 0.762)
			(end 1.524 0.762)
			(stroke
				(width 0.1524)
				(type default)
			)
			(layer "B.SilkS")
		)
		(fp_line
			(start 1.524 -0.762)
			(end -1.524 -0.762)
			(stroke
				(width 0.1524)
				(type default)
			)
			(layer "B.SilkS")
		)
		(fp_line
			(start 1.524 0.762)
			(end 1.524 -0.762)
			(stroke
				(width 0.1524)
				(type default)
			)
			(layer "B.SilkS")
		)
		(fp_line
			(start -1.1049 -0.724916)
			(end 1.1049 -0.724916)
			(stroke
				(width 0.1)
				(type default)
			)
			(layer "B.Fab")
		)
		(fp_line
			(start -1.1049 0.724916)
			(end -1.1049 -0.724916)
			(stroke
				(width 0.1)
				(type default)
			)
			(layer "B.Fab")
		)
		(fp_line
			(start 1.1049 -0.724916)
			(end 1.1049 0.724916)
			(stroke
				(width 0.1)
				(type default)
			)
			(layer "B.Fab")
		)
		(fp_line
			(start 1.1049 0.724916)
			(end -1.1049 0.724916)
			(stroke
				(width 0.1)
				(type default)
			)
			(layer "B.Fab")
		)
		(pad "1" smd rect
			(at 0.889 0)
			(size 1.016 1.27)
			(layers "B.Cu" "B.Mask" "B.Paste")
			(net "PVCCFA_EHV_CPU0")
		)
		(pad "2" smd rect
			(at -0.889 0)
			(size 1.016 1.27)
			(layers "B.Cu" "B.Mask" "B.Paste")
			(net "GND")
		)
	)
)
